(kicad_pcb
	(version 20260206)
	(generator "pcbnew")
	(generator_version "10.0")
	(general
		(thickness 1.6)
		(legacy_teardrops no)
	)
	(paper "A4")
	(title_block
		(title "Wiwynn_Tioga_Pass_MB.brd")
		(comment 1 "Tioga Pass / footprint 1465 of 4770 (J1F1), pads 72-76 of 76")
	)
	(layers
		(0 "F.Cu" signal "TOP")
		(4 "In1.Cu" signal "L2GND")
		(6 "In2.Cu" signal "L3")
		(8 "In3.Cu" signal "L4GND")
		(10 "In4.Cu" signal "L5")
		(12 "In5.Cu" signal "L6GND")
		(14 "In6.Cu" signal "L7VCC")
		(16 "In7.Cu" signal "L8VCC")
		(18 "In8.Cu" signal "L9GND")
		(20 "In9.Cu" signal "L10")
		(22 "In10.Cu" signal "L11GND")
		(24 "In11.Cu" signal "L12")
		(26 "In12.Cu" signal "L13GND")
		(2 "B.Cu" signal "BOTTOM")
		(9 "F.Adhes" user "F.Adhesive")
		(11 "B.Adhes" user "B.Adhesive")
		(13 "F.Paste" user "Package Geometry/Pastemask Top")
		(15 "B.Paste" user "Package Geometry/Pastemask Bottom")
		(5 "F.SilkS" user "Ref Des/Silkscreen Top")
		(7 "B.SilkS" user "Ref Des/Silkscreen Bottom")
		(1 "F.Mask" user "Board Geometry/Soldermask Top")
		(3 "B.Mask" user "Board Geometry/Soldermask Bottom")
		(17 "Dwgs.User" user "User.Drawings")
		(19 "Cmts.User" user "User.Comments")
		(21 "Eco1.User" user "User.Eco1")
		(23 "Eco2.User" user "User.Eco2")
		(25 "Edge.Cuts" user "Board Geometry/Outline")
		(27 "Margin" user)
		(31 "F.CrtYd" user "Package Geometry/Place Bound Top")
		(29 "B.CrtYd" user "Package Geometry/Place Bound Bottom")
		(35 "F.Fab" user "Ref Des/Assembly Top")
		(33 "B.Fab" user "Ref Des/Assembly Bottom")
	)
	(footprint ""
		(layer "F.Cu")
		(at 2.29997 -32.71012 -90)
		(property "Reference" "J1F1"
			(at 0 0 270)
			(layer "F.SilkS")
			(hide yes)
			(effects
				(font
					(size 1.27 1.27)
				)
			)
		)
		(property "Value" "*"
			(at -20.8026 -3.4036 270)
			(unlocked yes)
			(layer "F.Fab")
			(hide yes)
			(effects
				(font
					(size 1.27 1.016)
					(thickness 0.1524)
				)
			)
		)
		(property "Device Type" "DM-FCI-CONN76-8R-GP-U-01_CONN-A"
			(at -20.8026 -4.9276 270)
			(unlocked yes)
			(layer "F.Fab")
			(hide yes)
			(effects
				(font
					(size 1.27 1.016)
					(thickness 0.1524)
				)
			)
		)
		(duplicate_pad_numbers_are_jumpers no)
		(pad "I8" thru_hole circle
			(at 6.999986 -4.899914 270)
			(size 0.8128 0.8128)
			(drill 0.399796)
			(layers "*.Cu" "*.Mask")
			(remove_unused_layers no)
			(net "P3E_CPU1_PE3_MP_C_TXP<2>")
			(clearance 0.2921)
			(thermal_gap 0.2921)
		)
		(pad "J2" thru_hole circle
			(at -4.99999 -6.299962 270)
			(size 0.8636 0.8636)
			(drill 0.499872)
			(layers "*.Cu" "*.Mask")
			(remove_unused_layers no)
			(net "GND")
			(clearance 0.1778)
			(thermal_gap 0.1778)
		)
		(pad "J4" thru_hole circle
			(at -0.999998 -6.299962 270)
			(size 0.8636 0.8636)
			(drill 0.499872)
			(layers "*.Cu" "*.Mask")
			(remove_unused_layers no)
			(net "GND")
			(clearance 0.1778)
			(thermal_gap 0.1778)
		)
		(pad "J6" thru_hole circle
			(at 2.999994 -6.299962 270)
			(size 0.8636 0.8636)
			(drill 0.499872)
			(layers "*.Cu" "*.Mask")
			(remove_unused_layers no)
			(net "GND")
			(clearance 0.1778)
			(thermal_gap 0.1778)
		)
		(pad "J8" thru_hole circle
			(at 6.999986 -6.299962 270)
			(size 0.8636 0.8636)
			(drill 0.499872)
			(layers "*.Cu" "*.Mask")
			(remove_unused_layers no)
			(net "GND")
			(clearance 0.1778)
			(thermal_gap 0.1778)
		)
	)
)
